FILE_TYPE = CONNECTIVITY;
{Allegro Design Entry HDL 17.2-2016 S081 (4005846) 1/11/2022}
"PAGE_NUMBER" = 162;
0"NC";
1"AGND_HSC\g";
2"HSC_VDD\g";
3"AGND_HSC\g";
4"AGND_HSC\g";
5"AGND_HSC\g";
6"HSC_VDD\g";
7"HSC_FLT_TYPE";
8"HSC_D_OC_R";
9"HSC_VTEMP";
10"HSC_FAULT";
11"P12V_AUX\g";
12"HSC_FLT_TYPE_1";
13"HSC_D_OC_1";
14"HSC_NC1_1";
15"HSC_SS";
16"HSC_D_OC_R";
17"HSC_VTEMP";
18"HSC_FLT_TYPE";
19"HSC_FAULT";
20"HSC_FLT_TYPE_2";
21"P12V_AUX\g";
22"HSC_D_OC_2";
23"HSC_NC1_2";
24"HSC_SS";
25"P12V_PSU\g";
26"HSC_SCREF_1";
27"AGND_HSC\g";
28"HSC_IMON";
29"HSC_MODE_1";
30"HSC_SCREF";
31"HSC_CS_1";
32"HSC_OCREF";
33"AGND_HSC\g";
34"HSC_ON";
35"HSC_VDD_R_1";
36"P12V_PSU\g";
37"HSC_SCREF_2";
38"HSC_MODE_2";
39"HSC_SCREF";
40"HSC_CS_2";
41"HSC_IMON";
42"AGND_HSC\g";
43"HSC_OCREF";
44"AGND_HSC\g";
45"HSC_VDD_R_2";
46"HSC_ON";
%"UNIVERSAL_GND"
"1","(-2650,-2400)","0","pure_quanta_power","I1";
;
HDL_POWER"AGND_HSC"
CDS_LIB"pure_quanta_power";
"A"42;
%"Q_RES"
"1","(-1925,-1250)","0","pure_quanta","I11";
;
LOCATION"PR3912"
$SEC"1"
CDS_SEC"1"
PART_NUMBER"CS41202FB05"
PACK_TYPE"0402LF"
MATERIAL"CHIP"
TOLERANCE"1%"
VALUE"120K"
WATTAGE"1/16W"
CDS_LIB"pure_quanta";
"B"
$PN"2"38;
"A"
$PN"1"44;
%"Q_CAP"
"1","(-1975,-2075)","0","pure_quanta","I12";
;
LOCATION"PC2348"
$SEC"1"
CDS_SEC"1"
PART_NUMBER"CH21006KB16"
VALUE"1NF"
VOLTAGE"50V"
MATERIAL"EMPTY"
PACK_TYPE"0402"
TOLERANCE"10%"
CDS_LIB"pure_quanta";
"B"
$PN"2"42;
"A"
$PN"1"43;
%"Q_RES"
"2","(-1500,-2075)","0","pure_quanta","I13";
;
LOCATION"PR3915"
$SEC"1"
CDS_SEC"1"
VALUE"2K"
TOLERANCE"0.1%"
WATTAGE"1/16W"
PART_NUMBER"CS22002BB07"
PACK_TYPE"0402LF"
MATERIAL"CHIP"
CDS_LIB"pure_quanta";
"A"
$PN"1"40;
"B"
$PN"2"42;
%"Q_RES"
"2","(-975,-2075)","0","pure_quanta","I15";
;
$LOCATION"PR1101"
CDS_LOCATION"PR1101"
$SEC"1"
CDS_SEC"1"
PART_NUMBER"CS22002BB07"
PACK_TYPE"0402LF"
TOLERANCE"0.1%"
MATERIAL"CHIP"
WATTAGE"1/16W"
VALUE"2K"
CDS_LIB"pure_quanta";
"A"
$PN"1"41;
"B"
$PN"2"42;
%"MP5991GLUZ"
"1","(0,-1325)","0","pure_quanta","I16";
;
LOCATION"PU288"
SEC"1"
VALUE"MP5991GLU-Z"
PART_NUMBER"AL005991A00"
PART_TYPE"SMLF"
MATERIAL"IC"
NEEDS_NO_SIZE"TRUE"
CDS_LMAN_SYM_OUTLINE"-325,775,325,-775"
CDS_LIB"pure_quanta"
SEC_TYPE"";
"NC1"
$PN"7"23;
"FLT_TYPE"
$PN"6"20;
"SCREF_OCWREF"
$PN"17"37;
"MODE"
$PN"8"38;
"VOUT10"
$PN"32"21;
"VOUT9"
$PN"31"21;
"VOUT8"
$PN"30"21;
"VOUT7"
$PN"29"21;
"VOUT6"
$PN"28"21;
"VOUT5"
$PN"27"21;
"VIN9"
$PN"33"36;
"VIN8"
$PN"16"36;
"VIN7"
$PN"15"36;
"VIN6"
$PN"14"36;
"D_OC"
$PN"3"22;
"VOUT4"
$PN"26"21;
"VOUT3"
$PN"25"21;
"VOUT2"
$PN"2"21;
"VOUT1"
$PN"1"21;
"VTEMP"
$PN"18"17;
"GOK"
$PN"5"19;
"SS"
$PN"19"24;
"GND"
$PN"20"42;
"VDD33"
$PN"21"45;
"IMON"
$PN"22"41;
"CS"
$PN"23"40;
"OCREF"
$PN"24"43;
"ON"
$PN"4"46;
"VIN5"
$PN"13"36;
"VIN4"
$PN"12"36;
"VIN3"
$PN"11"36;
"VIN2"
$PN"10"36;
"VIN1"
$PN"9"36;
%"Q_RES"
"1","(-1325,-1425)","0","pure_quanta","I17";
;
LOCATION"PR3917"
$SEC"1"
CDS_SEC"1"
PART_NUMBER"CS00002JB13"
PACK_TYPE"0402LF"
VALUE"0"
TOLERANCE"5%"
MATERIAL"CHIP"
WATTAGE"1/16W"
CDS_LIB"pure_quanta";
"B"
$PN"2"37;
"A"
$PN"1"39;
%"UNIVERSAL_POWER"
"1","(-975,-450)","0","pure_quanta_power","I18";
;
HDL_POWER"P12V_PSU"
ROOM"AUX_SW"
BOM_COST"MIO_VRD_SB"
CDS_LIB"pure_quanta_power";
"A"36;
%"UNIVERSAL_GND"
"1","(-3450,1075)","0","pure_quanta_power","I19";
;
HDL_POWER"AGND_HSC"
CDS_LIB"pure_quanta_power";
"A"1;
%"Q_CAP"
"1","(-2650,-2075)","0","pure_quanta","I2";
;
LOCATION"PC2183"
$SEC"1"
CDS_SEC"1"
PART_NUMBER"TMP_QCH12206KB14"
PACK_TYPE"0402"
VALUE"220PF"
VOLTAGE"50V"
MATERIAL"EMPTY"
CDS_LIB"pure_quanta"
TOLERANCE"10%";
"B"
$PN"2"42;
"A"
$PN"1"46;
%"Q_CAP"
"1","(-3450,1375)","0","pure_quanta","I20";
;
LOCATION"PC1525"
$SEC"1"
CDS_SEC"1"
VALUE"1UF"
VOLTAGE"25V"
PART_NUMBER"CH5104KEB02"
MATERIAL"X6S"
PACK_TYPE"C0402"
CDS_LIB"pure_quanta"
TOLERANCE"10%";
"B"
$PN"2"1;
"A"
$PN"1"35;
%"Q_RES"
"1","(-3450,1850)","1","pure_quanta","I21";
;
LOCATION"PR3910"
$SEC"1"
CDS_SEC"1"
WATTAGE"1/16W"
PACK_TYPE"0402LF"
MATERIAL"CHIP"
TOLERANCE"5%"
VALUE"0"
PART_NUMBER"CS00002JB13"
CDS_LIB"pure_quanta";
"B"
$PN"2"2;
"A"
$PN"1"35;
%"UNIVERSAL_POWER"
"1","(-3450,2100)","0","pure_quanta_power","I22";
;
HDL_POWER"HSC_VDD"
ROOM"AUX_SW"
CDS_LIB"pure_quanta_power"
BOM_COST"MIO_VRD_SB";
"A"2;
%"UNIVERSAL_GND"
"1","(-2675,425)","0","pure_quanta_power","I23";
;
HDL_POWER"AGND_HSC"
CDS_LIB"pure_quanta_power";
"A"27;
%"Q_CAP"
"1","(-2675,725)","0","pure_quanta","I24";
;
LOCATION"PC2182"
$SEC"1"
CDS_SEC"1"
MATERIAL"X7R"
PART_NUMBER"TMP_QCH12206KB14"
PACK_TYPE"0402"
VALUE"220PF"
VOLTAGE"50V"
TOLERANCE"10%"
CDS_LIB"pure_quanta";
"B"
$PN"2"27;
"A"
$PN"1"34;
%"UNIVERSAL_GND"
"1","(-2625,1475)","0","pure_quanta_power","I27";
;
HDL_POWER"AGND_HSC"
CDS_LIB"pure_quanta_power";
"A"33;
%"Q_RES"
"1","(-1925,1550)","0","pure_quanta","I29";
;
$LOCATION"PR1134"
CDS_LOCATION"PR1134"
$SEC"1"
CDS_SEC"1"
PACK_TYPE"0402LF"
TOLERANCE"1%"
MATERIAL"CHIP"
VALUE"120K"
PART_NUMBER"CS41202FB05"
WATTAGE"1/16W"
CDS_LIB"pure_quanta";
"B"
$PN"2"29;
"A"
$PN"1"33;
%"UNIVERSAL_GND"
"1","(-3475,-1725)","0","pure_quanta_power","I3";
;
HDL_POWER"AGND_HSC"
CDS_LIB"pure_quanta_power";
"A"3;
%"Q_CAP"
"1","(-2000,725)","0","pure_quanta","I30";
;
LOCATION"PC2347"
$SEC"1"
CDS_SEC"1"
PACK_TYPE"0402"
MATERIAL"EMPTY"
VOLTAGE"50V"
VALUE"1NF"
PART_NUMBER"CH21006KB16"
TOLERANCE"10%"
CDS_LIB"pure_quanta";
"B"
$PN"2"27;
"A"
$PN"1"32;
%"Q_RES"
"2","(-1500,725)","0","pure_quanta","I31";
;
LOCATION"PR3914"
$SEC"1"
CDS_SEC"1"
PACK_TYPE"0402LF"
PART_NUMBER"CS22002BB07"
MATERIAL"CHIP"
WATTAGE"1/16W"
TOLERANCE"0.1%"
VALUE"2K"
CDS_LIB"pure_quanta";
"A"
$PN"1"31;
"B"
$PN"2"27;
%"Q_RES"
"1","(-1350,1375)","0","pure_quanta","I33";
;
LOCATION"PR3916"
$SEC"1"
CDS_SEC"1"
WATTAGE"1/16W"
MATERIAL"CHIP"
PACK_TYPE"0402LF"
TOLERANCE"5%"
VALUE"0"
PART_NUMBER"CS00002JB13"
CDS_LIB"pure_quanta";
"B"
$PN"2"26;
"A"
$PN"1"30;
%"Q_RES"
"2","(-975,725)","0","pure_quanta","I34";
;
LOCATION"PR3918"
$SEC"1"
CDS_SEC"1"
MATERIAL"CHIP"
WATTAGE"1/16W"
PART_NUMBER"CS22002BB07"
PACK_TYPE"0402LF"
TOLERANCE"0.1%"
VALUE"2K"
CDS_LIB"pure_quanta";
"A"
$PN"1"28;
"B"
$PN"2"27;
%"MP5991GLUZ"
"1","(0,1475)","0","pure_quanta","I35";
;
LOCATION"PU287"
SEC"1"
MATERIAL"IC"
PART_NUMBER"AL005991A00"
VALUE"MP5991GLU-Z"
PART_TYPE"SMLF"
CDS_LIB"pure_quanta"
CDS_LMAN_SYM_OUTLINE"-325,775,325,-775"
NEEDS_NO_SIZE"TRUE"
SEC_TYPE"";
"NC1"
$PN"7"14;
"FLT_TYPE"
$PN"6"12;
"SCREF_OCWREF"
$PN"17"26;
"MODE"
$PN"8"29;
"VOUT10"
$PN"32"11;
"VOUT9"
$PN"31"11;
"VOUT8"
$PN"30"11;
"VOUT7"
$PN"29"11;
"VOUT6"
$PN"28"11;
"VOUT5"
$PN"27"11;
"VIN9"
$PN"33"25;
"VIN8"
$PN"16"25;
"VIN7"
$PN"15"25;
"VIN6"
$PN"14"25;
"D_OC"
$PN"3"13;
"VOUT4"
$PN"26"11;
"VOUT3"
$PN"25"11;
"VOUT2"
$PN"2"11;
"VOUT1"
$PN"1"11;
"VTEMP"
$PN"18"9;
"GOK"
$PN"5"10;
"SS"
$PN"19"15;
"GND"
$PN"20"27;
"VDD33"
$PN"21"35;
"IMON"
$PN"22"28;
"CS"
$PN"23"31;
"OCREF"
$PN"24"32;
"ON"
$PN"4"34;
"VIN5"
$PN"13"25;
"VIN4"
$PN"12"25;
"VIN3"
$PN"11"25;
"VIN2"
$PN"10"25;
"VIN1"
$PN"9"25;
%"UNIVERSAL_POWER"
"1","(-975,2350)","0","pure_quanta_power","I36";
;
HDL_POWER"P12V_PSU"
ROOM"AUX_SW"
CDS_LIB"pure_quanta_power"
BOM_COST"MIO_VRD_SB";
"A"25;
%"UNIVERSAL_GND"
"1","(975,-2275)","0","pure_quanta_power","I37";
;
HDL_POWER"AGND_HSC"
CDS_LIB"pure_quanta_power";
"A"4;
%"Q_CAP"
"1","(975,-2050)","0","pure_quanta","I38";
;
LOCATION"PC2185"
$SEC"1"
CDS_SEC"1"
VALUE"0.068UF"
VOLTAGE"16V"
MATERIAL"X7R"
PART_NUMBER"CH3683K1B09"
PACK_TYPE"0402"
CDS_LIB"pure_quanta"
TOLERANCE"10%";
"B"
$PN"2"4;
"A"
$PN"1"24;
%"Q_RES"
"1","(1475,-1500)","0","pure_quanta","I39";
;
LOCATION"PR3922"
$SEC"1"
CDS_SEC"1"
PART_NUMBER"CS00002JB13"
VALUE"0"
TOLERANCE"5%"
MATERIAL"CHIP"
WATTAGE"1/16W"
PACK_TYPE"0402LF"
CDS_LIB"pure_quanta";
"B"
$PN"2"18;
"A"
$PN"1"20;
%"Q_CAP"
"1","(-3475,-1425)","0","pure_quanta","I4";
;
LOCATION"PC2181"
$SEC"1"
CDS_SEC"1"
VALUE"1UF"
PART_NUMBER"CH5104KEB02"
PACK_TYPE"C0402"
MATERIAL"X6S"
VOLTAGE"25V"
CDS_LIB"pure_quanta"
TOLERANCE"10%";
"B"
$PN"2"3;
"A"
$PN"1"45;
%"Q_RES"
"1","(1475,-1325)","0","pure_quanta","I40";
;
LOCATION"PR3921"
$SEC"1"
CDS_SEC"1"
TOLERANCE"5%"
PACK_TYPE"0402LF"
VALUE"0"
PART_NUMBER"CS00002JB13"
WATTAGE"1/16W"
MATERIAL"CHIP"
CDS_LIB"pure_quanta";
"B"
$PN"2"16;
"A"
$PN"1"22;
%"UNIVERSAL_POWER"
"1","(1100,-450)","0","pure_quanta_power","I41";
;
HDL_POWER"P12V_AUX"
ROOM"AUX_SW"
BOM_COST"MIO_VRD_SB"
CDS_LIB"pure_quanta_power";
"A"21;
%"Q_CAP"
"1","(975,750)","0","pure_quanta","I47";
;
LOCATION"PC2184"
$SEC"1"
CDS_SEC"1"
VALUE"0.068UF"
MATERIAL"X7R"
PACK_TYPE"0402"
VOLTAGE"16V"
PART_NUMBER"CH3683K1B09"
CDS_LIB"pure_quanta"
TOLERANCE"10%";
"B"
$PN"2"5;
"A"
$PN"1"15;
%"UNIVERSAL_GND"
"1","(975,525)","0","pure_quanta_power","I48";
;
HDL_POWER"AGND_HSC"
CDS_LIB"pure_quanta_power";
"A"5;
%"Q_RES"
"1","(1475,1300)","0","pure_quanta","I49";
;
LOCATION"PR3920"
$SEC"1"
CDS_SEC"1"
PART_NUMBER"CS00002JB13"
PACK_TYPE"0402LF"
MATERIAL"CHIP"
TOLERANCE"5%"
VALUE"0"
WATTAGE"1/16W"
CDS_LIB"pure_quanta";
"B"
$PN"2"7;
"A"
$PN"1"12;
%"Q_RES"
"1","(-3475,-950)","1","pure_quanta","I5";
;
LOCATION"PR3911"
$SEC"1"
CDS_SEC"1"
TOLERANCE"5%"
MATERIAL"CHIP"
WATTAGE"1/16W"
PACK_TYPE"0402LF"
PART_NUMBER"CS00002JB13"
VALUE"0"
CDS_LIB"pure_quanta";
"B"
$PN"2"6;
"A"
$PN"1"45;
%"Q_RES"
"1","(1475,1475)","0","pure_quanta","I50";
;
LOCATION"PR3919"
$SEC"1"
CDS_SEC"1"
WATTAGE"1/16W"
PART_NUMBER"CS00002JB13"
PACK_TYPE"0402LF"
VALUE"0"
TOLERANCE"5%"
MATERIAL"CHIP"
CDS_LIB"pure_quanta";
"B"
$PN"2"8;
"A"
$PN"1"13;
%"UNIVERSAL_POWER"
"1","(1100,2350)","0","pure_quanta_power","I51";
;
HDL_POWER"P12V_AUX"
ROOM"AUX_SW"
CDS_LIB"pure_quanta_power"
BOM_COST"MIO_VRD_SB";
"A"11;
%"UNIVERSAL_POWER"
"1","(-3475,-700)","0","pure_quanta_power","I6";
;
HDL_POWER"HSC_VDD"
ROOM"AUX_SW"
CDS_LIB"pure_quanta_power"
BOM_COST"MIO_VRD_SB";
"A"6;
%"UNIVERSAL_GND"
"1","(-2725,-1350)","0","pure_quanta_power","I8";
;
HDL_POWER"AGND_HSC"
CDS_LIB"pure_quanta_power";
"A"44;
END.
